# BASEBOARD_FAB2 (Tioga Pass) — schematic netlist excerpt (pin names and nets, part order shuffled) for the footprints in the layout excerpt that follows; sources: Cadence DE-HDL packaged netlist, KiCad conversion of Wiwynn_Tioga_Pass_MB.brd

C2L42  CAP_A  0.01UF 25V 10% X7R  pkg 0402V  page 173 : A = SATA6G_P2_TX_C_DN ; B = SATA6G_PCH_PCIE_UP_SATA_TXN<2>
C32W5  CAP  1.0UF 16V 10% X6S  pkg 0402  page 185 : A = P1V8_M2 ; B = GND
R25W38  120R2F-GP  1%  pkg RCL_GP  page 151 : \1\ = BMC_M_A0 ; \2\ = P1V2_AUX_BMC

(kicad_pcb
	(version 20260206)
	(generator "pcbnew")
	(generator_version "10.0")
	(general
		(thickness 1.6)
		(legacy_teardrops no)
	)
	(paper "A4")
	(title_block
		(title "Wiwynn_Tioga_Pass_MB.brd")
		(comment 1 "Tioga Pass / footprints 4079-4081 of 4770")
	)
	(layers
		(0 "F.Cu" signal "TOP")
		(4 "In1.Cu" signal "L2GND")
		(6 "In2.Cu" signal "L3")
		(8 "In3.Cu" signal "L4GND")
		(10 "In4.Cu" signal "L5")
		(12 "In5.Cu" signal "L6GND")
		(14 "In6.Cu" signal "L7VCC")
		(16 "In7.Cu" signal "L8VCC")
		(18 "In8.Cu" signal "L9GND")
		(20 "In9.Cu" signal "L10")
		(22 "In10.Cu" signal "L11GND")
		(24 "In11.Cu" signal "L12")
		(26 "In12.Cu" signal "L13GND")
		(2 "B.Cu" signal "BOTTOM")
		(9 "F.Adhes" user "F.Adhesive")
		(11 "B.Adhes" user "B.Adhesive")
		(13 "F.Paste" user "Package Geometry/Pastemask Top")
		(15 "B.Paste" user "Package Geometry/Pastemask Bottom")
		(5 "F.SilkS" user "Ref Des/Silkscreen Top")
		(7 "B.SilkS" user "Ref Des/Silkscreen Bottom")
		(1 "F.Mask" user "Board Geometry/Soldermask Top")
		(3 "B.Mask" user "Board Geometry/Soldermask Bottom")
		(17 "Dwgs.User" user "User.Drawings")
		(19 "Cmts.User" user "User.Comments")
		(21 "Eco1.User" user "User.Eco1")
		(23 "Eco2.User" user "User.Eco2")
		(25 "Edge.Cuts" user "Board Geometry/Outline")
		(27 "Margin" user)
		(31 "F.CrtYd" user "Package Geometry/Place Bound Top")
		(29 "B.CrtYd" user "Package Geometry/Place Bound Bottom")
		(35 "F.Fab" user "Ref Des/Assembly Top")
		(33 "B.Fab" user "Ref Des/Assembly Bottom")
	)
	(footprint ""
		(layer "B.Cu")
		(at 448.544188 -37.032692 90)
		(property "Reference" "R25W38"
			(at 0 0 90)
			(layer "B.SilkS")
			(hide yes)
			(effects
				(font
					(size 1.27 1.27)
				)
				(justify mirror)
			)
		)
		(property "Value" "*"
			(at -0.064008 -4.108196 90)
			(unlocked yes)
			(layer "B.Fab")
			(hide yes)
			(effects
				(font
					(size 1.27 1.016)
					(thickness 0.1524)
				)
				(justify mirror)
			)
		)
		(property "Device Type" "120R2F-GP_RCL_GP-120R2F-GP,64.A"
			(at -0.064008 -5.632196 90)
			(unlocked yes)
			(layer "B.Fab")
			(hide yes)
			(effects
				(font
					(size 1.27 1.016)
					(thickness 0.1524)
				)
				(justify mirror)
			)
		)
		(duplicate_pad_numbers_are_jumpers no)
		(fp_line
			(start 0.508 -0.9398)
			(end 0.508 0.9398)
			(stroke
				(width 0.1524)
				(type default)
			)
			(layer "B.SilkS")
		)
		(fp_line
			(start -0.508 -0.9398)
			(end 0.508 -0.9398)
			(stroke
				(width 0.1524)
				(type default)
			)
			(layer "B.SilkS")
		)
		(fp_rect
			(start 0.508 0.9398)
			(end -0.508 -0.9398)
			(stroke
				(width 0)
				(type default)
			)
			(fill no)
			(layer "B.CrtYd")
		)
		(fp_rect
			(start 0.508 0.9398)
			(end -0.508 -0.9398)
			(stroke
				(width 0)
				(type default)
			)
			(fill no)
			(layer "B.Fab")
		)
		(pad "1" smd custom
			(at 0 -0.4445 270)
			(size 0.1397 0.1397)
			(layers "B.Cu" "B.Mask" "B.Paste")
			(net "BMC_M_A0")
			(options
				(clearance outline)
				(anchor circle)
			)
			(primitives
				(gr_poly
					(pts
						(arc
							(start -0.1778 0.2794)
							(mid -0.249642 0.249642)
							(end -0.2794 0.1778)
						)
						(arc
							(start -0.2794 -0.1778)
							(mid -0.249642 -0.249642)
							(end -0.1778 -0.2794)
						)
						(arc
							(start 0.1778 -0.2794)
							(mid 0.249642 -0.249642)
							(end 0.2794 -0.1778)
						)
						(arc
							(start 0.2794 0.1778)
							(mid 0.249642 0.249642)
							(end 0.1778 0.2794)
						)
					)
					(width 0)
					(fill yes)
				)
			)
		)
		(pad "2" smd custom
			(at 0 0.4445 270)
			(size 0.1397 0.1397)
			(layers "B.Cu" "B.Mask" "B.Paste")
			(net "P1V2_AUX_BMC")
			(options
				(clearance outline)
				(anchor circle)
			)
			(primitives
				(gr_poly
					(pts
						(arc
							(start -0.1778 0.2794)
							(mid -0.249642 0.249642)
							(end -0.2794 0.1778)
						)
						(arc
							(start -0.2794 -0.1778)
							(mid -0.249642 -0.249642)
							(end -0.1778 -0.2794)
						)
						(arc
							(start 0.1778 -0.2794)
							(mid 0.249642 -0.249642)
							(end 0.2794 -0.1778)
						)
						(arc
							(start 0.2794 0.1778)
							(mid 0.249642 0.249642)
							(end 0.1778 0.2794)
						)
					)
					(width 0)
					(fill yes)
				)
			)
		)
	)
	(footprint ""
		(layer "B.Cu")
		(at 394.171932 -25.143714 180)
		(property "Reference" "C32W5"
			(at 0.8382 -0.67818 180)
			(unlocked yes)
			(layer "B.SilkS")
			(effects
				(font
					(size 0.4064 0.254)
					(thickness 0.1524)
				)
				(justify left mirror)
			)
		)
		(property "Value" ""
			(at 0 0 0)
			(layer "B.Fab")
			(effects
				(font
					(size 1.27 1.27)
				)
				(justify mirror)
			)
		)
		(duplicate_pad_numbers_are_jumpers no)
		(fp_poly
			(pts
				(xy -0.3048 -0.1016) (xy -0.3048 0.9906) (xy 0.3048 0.9906) (xy 0.3048 -0.1016)
			)
			(stroke
				(width 0)
				(type default)
			)
			(fill no)
			(layer "B.CrtYd")
		)
		(fp_line
			(start 0.3048 0.9906)
			(end -0.3048 0.9906)
			(stroke
				(width 0.1)
				(type default)
			)
			(layer "B.Fab")
		)
		(fp_line
			(start 0.3048 -0.1016)
			(end 0.3048 0.9906)
			(stroke
				(width 0.1)
				(type default)
			)
			(layer "B.Fab")
		)
		(fp_line
			(start -0.3048 0.9906)
			(end -0.3048 -0.1016)
			(stroke
				(width 0.1)
				(type default)
			)
			(layer "B.Fab")
		)
		(fp_line
			(start -0.3048 -0.1016)
			(end 0.3048 -0.1016)
			(stroke
				(width 0.1)
				(type default)
			)
			(layer "B.Fab")
		)
		(pad "1" smd rect
			(at 0 0)
			(size 0.508 0.508)
			(layers "B.Cu" "B.Mask" "B.Paste")
			(net "P1V8_M2")
		)
		(pad "2" smd rect
			(at 0 0.889)
			(size 0.508 0.508)
			(layers "B.Cu" "B.Mask" "B.Paste")
			(net "GND")
		)
		(zone
			(layer "B.Cu")
			(hatch none 0.5)
			(connect_pads
				(clearance 0)
			)
			(min_thickness 0.25)
			(keepout
				(tracks not_allowed)
				(vias allowed)
				(pads allowed)
				(copperpour not_allowed)
				(footprints allowed)
			)
			(placement
				(enabled no)
				(sheetname "")
			)
			(fill
				(thermal_gap 0.5)
				(thermal_bridge_width 0.5)
				(island_removal_mode 0)
			)
			(polygon
				(pts
					(xy 393.917932 -25.778714) (xy 394.425932 -25.778714) (xy 394.425932 -25.397714) (xy 393.917932 -25.397714)
				)
			)
		)
		(zone
			(layer "B.Cu")
			(hatch none 0.5)
			(connect_pads
				(clearance 0)
			)
			(min_thickness 0.25)
			(keepout
				(tracks allowed)
				(vias not_allowed)
				(pads allowed)
				(copperpour not_allowed)
				(footprints allowed)
			)
			(placement
				(enabled no)
				(sheetname "")
			)
			(fill
				(thermal_gap 0.5)
				(thermal_bridge_width 0.5)
				(island_removal_mode 0)
			)
			(polygon
				(pts
					(xy 393.917932 -25.397714) (xy 394.425932 -25.397714) (xy 394.425932 -25.778714) (xy 393.917932 -25.778714)
				)
			)
		)
	)
	(footprint ""
		(layer "B.Cu")
		(at 424.18 -141.986)
		(property "Reference" "C2L42"
			(at 0 0 0)
			(layer "B.SilkS")
			(hide yes)
			(effects
				(font
					(size 1.27 1.27)
				)
				(justify mirror)
			)
		)
		(property "Value" ""
			(at 0 0 0)
			(layer "B.Fab")
			(effects
				(font
					(size 1.27 1.27)
				)
				(justify mirror)
			)
		)
		(duplicate_pad_numbers_are_jumpers no)
		(fp_poly
			(pts
				(xy -0.3048 -0.1016) (xy -0.3048 0.9906) (xy 0.3048 0.9906) (xy 0.3048 -0.1016)
			)
			(stroke
				(width 0)
				(type default)
			)
			(fill no)
			(layer "B.CrtYd")
		)
		(fp_line
			(start -0.3048 -0.1016)
			(end 0.3048 -0.1016)
			(stroke
				(width 0.1)
				(type default)
			)
			(layer "B.Fab")
		)
		(fp_line
			(start -0.3048 0.9906)
			(end -0.3048 -0.1016)
			(stroke
				(width 0.1)
				(type default)
			)
			(layer "B.Fab")
		)
		(fp_line
			(start 0.3048 -0.1016)
			(end 0.3048 0.9906)
			(stroke
				(width 0.1)
				(type default)
			)
			(layer "B.Fab")
		)
		(fp_line
			(start 0.3048 0.9906)
			(end -0.3048 0.9906)
			(stroke
				(width 0.1)
				(type default)
			)
			(layer "B.Fab")
		)
		(pad "1" smd rect
			(at 0 0 180)
			(size 0.508 0.508)
			(layers "B.Cu" "B.Mask" "B.Paste")
			(net "SATA6G_P2_TX_C_DN")
		)
		(pad "2" smd rect
			(at 0 0.889 180)
			(size 0.508 0.508)
			(layers "B.Cu" "B.Mask" "B.Paste")
			(net "SATA6G_PCH_PCIE_UP_SATA_TXN<2>")
		)
		(zone
			(layer "B.Cu")
			(hatch none 0.5)
			(connect_pads
				(clearance 0)
			)
			(min_thickness 0.25)
			(keepout
				(tracks allowed)
				(vias not_allowed)
				(pads allowed)
				(copperpour not_allowed)
				(footprints allowed)
			)
			(placement
				(enabled no)
				(sheetname "")
			)
			(fill
				(thermal_gap 0.5)
				(thermal_bridge_width 0.5)
				(island_removal_mode 0)
			)
			(polygon
				(pts
					(xy 424.434 -141.732) (xy 423.926 -141.732) (xy 423.926 -141.351) (xy 424.434 -141.351)
				)
			)
		)
		(zone
			(layer "B.Cu")
			(hatch none 0.5)
			(connect_pads
				(clearance 0)
			)
			(min_thickness 0.25)
			(keepout
				(tracks not_allowed)
				(vias allowed)
				(pads allowed)
				(copperpour not_allowed)
				(footprints allowed)
			)
			(placement
				(enabled no)
				(sheetname "")
			)
			(fill
				(thermal_gap 0.5)
				(thermal_bridge_width 0.5)
				(island_removal_mode 0)
			)
			(polygon
				(pts
					(xy 424.434 -141.351) (xy 423.926 -141.351) (xy 423.926 -141.732) (xy 424.434 -141.732)
				)
			)
		)
	)
)
